(kicad_sch
	(version 20250114)
	(generator "eeschema")
	(generator_version "9.0")
	(paper "A3")
	(title_block
		(title "RDIMM DDR5 Tester")
		(date "2026-05-21")
		(rev "2.2.0")
		(company "Antmicro")
		(comment 1 "www.antmicro.com")
		(comment 2 "Antmicro")
	)
	(text "HyperRAM"
		(exclude_from_sim no)
		(at 13.97 19.05 0)
		(effects
			(font
				(size 3 3)
				(thickness 0.6)
				(bold yes)
			)
			(justify left bottom)
		)
	)
	(text "(Q)SPI flash"
		(exclude_from_sim no)
		(at 14.605 142.875 0)
		(effects
			(font
				(size 3 3)
				(thickness 0.6)
				(bold yes)
			)
			(justify left bottom)
		)
	)
	(text "Master SPI Quad (x4) configuration scheme\nFollows FPGAs Configuration User Guide UG570"
		(exclude_from_sim no)
		(at 15.24 153.67 0)
		(effects
			(font
				(size 2 2)
			)
			(justify left bottom)
		)
	)
	(junction
		(at 199.39 212.09)
		(diameter 0)
		(color 0 0 0 0)
	)
	(junction
		(at 191.77 46.99)
		(diameter 0)
		(color 0 0 0 0)
	)
	(junction
		(at 233.68 57.15)
		(diameter 0)
		(color 0 0 0 0)
	)
	(junction
		(at 208.28 185.42)
		(diameter 0)
		(color 0 0 0 0)
	)
	(junction
		(at 233.68 95.25)
		(diameter 0)
		(color 0 0 0 0)
	)
	(junction
		(at 199.39 185.42)
		(diameter 0)
		(color 0 0 0 0)
	)
	(junction
		(at 191.77 57.15)
		(diameter 0)
		(color 0 0 0 0)
	)
	(junction
		(at 236.22 209.55)
		(diameter 0)
		(color 0 0 0 0)
	)
	(junction
		(at 256.54 57.15)
		(diameter 0)
		(color 0 0 0 0)
	)
	(junction
		(at 195.58 59.69)
		(diameter 0)
		(color 0 0 0 0)
	)
	(junction
		(at 248.92 57.15)
		(diameter 0)
		(color 0 0 0 0)
	)
	(junction
		(at 215.9 204.47)
		(diameter 0)
		(color 0 0 0 0)
	)
	(junction
		(at 264.16 57.15)
		(diameter 0)
		(color 0 0 0 0)
	)
	(junction
		(at 158.75 199.39)
		(diameter 0)
		(color 0 0 0 0)
	)
	(junction
		(at 208.28 207.01)
		(diameter 0)
		(color 0 0 0 0)
	)
	(junction
		(at 240.03 57.15)
		(diameter 0)
		(color 0 0 0 0)
	)
	(bus_entry
		(at 170.18 82.55)
		(size 2.54 2.54)
		(stroke
			(width 0)
			(type default)
		)
	)
	(bus_entry
		(at 170.18 87.63)
		(size 2.54 2.54)
		(stroke
			(width 0)
			(type default)
		)
	)
	(bus_entry
		(at 170.18 62.23)
		(size 2.54 2.54)
		(stroke
			(width 0)
			(type default)
		)
	)
	(bus_entry
		(at 170.18 80.01)
		(size 2.54 2.54)
		(stroke
			(width 0)
			(type default)
		)
	)
	(bus_entry
		(at 170.18 77.47)
		(size 2.54 2.54)
		(stroke
			(width 0)
			(type default)
		)
	)
	(bus_entry
		(at 248.92 207.01)
		(size 2.54 -2.54)
		(stroke
			(width 0)
			(type default)
		)
	)
	(bus_entry
		(at 248.92 212.09)
		(size 2.54 -2.54)
		(stroke
			(width 0)
			(type default)
		)
	)
	(bus_entry
		(at 170.18 74.93)
		(size 2.54 2.54)
		(stroke
			(width 0)
			(type default)
		)
	)
	(bus_entry
		(at 170.18 69.85)
		(size 2.54 2.54)
		(stroke
			(width 0)
			(type default)
		)
	)
	(bus_entry
		(at 248.92 209.55)
		(size 2.54 -2.54)
		(stroke
			(width 0)
			(type default)
		)
	)
	(bus_entry
		(at 170.18 92.71)
		(size 2.54 2.54)
		(stroke
			(width 0)
			(type default)
		)
	)
	(bus_entry
		(at 248.92 201.93)
		(size 2.54 -2.54)
		(stroke
			(width 0)
			(type default)
		)
	)
	(bus_entry
		(at 170.18 64.77)
		(size 2.54 2.54)
		(stroke
			(width 0)
			(type default)
		)
	)
	(bus_entry
		(at 170.18 85.09)
		(size 2.54 2.54)
		(stroke
			(width 0)
			(type default)
		)
	)
	(bus_entry
		(at 170.18 72.39)
		(size 2.54 2.54)
		(stroke
			(width 0)
			(type default)
		)
	)
	(bus_entry
		(at 248.92 204.47)
		(size 2.54 -2.54)
		(stroke
			(width 0)
			(type default)
		)
	)
	(bus_entry
		(at 170.18 54.61)
		(size 2.54 2.54)
		(stroke
			(width 0)
			(type default)
		)
	)
	(bus_entry
		(at 248.92 199.39)
		(size 2.54 -2.54)
		(stroke
			(width 0)
			(type default)
		)
	)
	(bus_entry
		(at 170.18 57.15)
		(size 2.54 2.54)
		(stroke
			(width 0)
			(type default)
		)
	)
	(bus
		(pts
			(xy 170.18 87.63) (xy 170.18 92.71)
		)
		(stroke
			(width 0)
			(type default)
		)
	)
	(wire
		(pts
			(xy 189.23 199.39) (xy 226.06 199.39)
		)
		(stroke
			(width 0)
			(type default)
		)
	)
	(bus
		(pts
			(xy 170.18 80.01) (xy 170.18 82.55)
		)
		(stroke
			(width 0)
			(type default)
		)
	)
	(bus
		(pts
			(xy 170.18 85.09) (xy 170.18 87.63)
		)
		(stroke
			(width 0)
			(type default)
		)
	)
	(wire
		(pts
			(xy 240.03 59.69) (xy 240.03 57.15)
		)
		(stroke
			(width 0)
			(type default)
		)
	)
	(bus
		(pts
			(xy 251.46 199.39) (xy 251.46 201.93)
		)
		(stroke
			(width 0)
			(type default)
		)
	)
	(bus
		(pts
			(xy 251.46 195.58) (xy 251.46 196.85)
		)
		(stroke
			(width 0)
			(type default)
		)
	)
	(wire
		(pts
			(xy 195.58 54.61) (xy 195.58 59.69)
		)
		(stroke
			(width 0)
			(type default)
		)
	)
	(wire
		(pts
			(xy 256.54 66.04) (xy 256.54 64.77)
		)
		(stroke
			(width 0)
			(type default)
		)
	)
	(wire
		(pts
			(xy 240.03 57.15) (xy 248.92 57.15)
		)
		(stroke
			(width 0)
			(type default)
		)
	)
	(bus
		(pts
			(xy 170.18 74.93) (xy 170.18 77.47)
		)
		(stroke
			(width 0)
			(type default)
		)
	)
	(wire
		(pts
			(xy 172.72 80.01) (xy 200.66 80.01)
		)
		(stroke
			(width 0)
			(type default)
		)
	)
	(wire
		(pts
			(xy 199.39 184.15) (xy 199.39 185.42)
		)
		(stroke
			(width 0)
			(type default)
		)
	)
	(wire
		(pts
			(xy 167.64 212.09) (xy 167.64 213.36)
		)
		(stroke
			(width 0)
			(type default)
		)
	)
	(wire
		(pts
			(xy 172.72 90.17) (xy 200.66 90.17)
		)
		(stroke
			(width 0)
			(type default)
		)
	)
	(wire
		(pts
			(xy 231.14 95.25) (xy 233.68 95.25)
		)
		(stroke
			(width 0)
			(type default)
		)
	)
	(wire
		(pts
			(xy 231.14 201.93) (xy 248.92 201.93)
		)
		(stroke
			(width 0)
			(type default)
		)
	)
	(bus
		(pts
			(xy 255.27 194.31) (xy 252.73 194.31)
		)
		(stroke
			(width 0)
			(type default)
		)
	)
	(polyline
		(pts
			(xy 12.7 135.89) (xy 407.67 135.89)
		)
		(stroke
			(width 0)
			(type default)
		)
	)
	(wire
		(pts
			(xy 240.03 66.04) (xy 240.03 64.77)
		)
		(stroke
			(width 0)
			(type default)
		)
	)
	(wire
		(pts
			(xy 199.39 212.09) (xy 248.92 212.09)
		)
		(stroke
			(width 0)
			(type default)
		)
	)
	(bus
		(pts
			(xy 170.18 53.34) (xy 170.18 54.61)
		)
		(stroke
			(width 0)
			(type default)
		)
	)
	(wire
		(pts
			(xy 215.9 194.31) (xy 215.9 204.47)
		)
		(stroke
			(width 0)
			(type default)
		)
	)
	(bus
		(pts
			(xy 170.18 57.15) (xy 170.18 62.23)
		)
		(stroke
			(width 0)
			(type default)
		)
	)
	(wire
		(pts
			(xy 199.39 212.09) (xy 199.39 194.31)
		)
		(stroke
			(width 0)
			(type default)
		)
	)
	(bus
		(pts
			(xy 251.46 195.58) (xy 252.73 194.31)
		)
		(stroke
			(width 0)
			(type default)
		)
	)
	(wire
		(pts
			(xy 172.72 85.09) (xy 200.66 85.09)
		)
		(stroke
			(width 0)
			(type default)
		)
	)
	(wire
		(pts
			(xy 191.77 45.72) (xy 191.77 46.99)
		)
		(stroke
			(width 0)
			(type default)
		)
	)
	(wire
		(pts
			(xy 215.9 204.47) (xy 226.06 204.47)
		)
		(stroke
			(width 0)
			(type default)
		)
	)
	(wire
		(pts
			(xy 233.68 57.15) (xy 240.03 57.15)
		)
		(stroke
			(width 0)
			(type default)
		)
	)
	(wire
		(pts
			(xy 208.28 207.01) (xy 226.06 207.01)
		)
		(stroke
			(width 0)
			(type default)
		)
	)
	(wire
		(pts
			(xy 236.22 209.55) (xy 248.92 209.55)
		)
		(stroke
			(width 0)
			(type default)
		)
	)
	(wire
		(pts
			(xy 158.75 199.39) (xy 168.91 199.39)
		)
		(stroke
			(width 0)
			(type default)
		)
	)
	(wire
		(pts
			(xy 264.16 55.88) (xy 264.16 57.15)
		)
		(stroke
			(width 0)
			(type default)
		)
	)
	(bus
		(pts
			(xy 170.18 54.61) (xy 170.18 57.15)
		)
		(stroke
			(width 0)
			(type default)
		)
	)
	(bus
		(pts
			(xy 167.64 52.07) (xy 168.91 52.07)
		)
		(stroke
			(width 0)
			(type default)
		)
	)
	(bus
		(pts
			(xy 170.18 82.55) (xy 170.18 85.09)
		)
		(stroke
			(width 0)
			(type default)
		)
	)
	(wire
		(pts
			(xy 231.14 57.15) (xy 233.68 57.15)
		)
		(stroke
			(width 0)
			(type default)
		)
	)
	(wire
		(pts
			(xy 256.54 57.15) (xy 264.16 57.15)
		)
		(stroke
			(width 0)
			(type default)
		)
	)
	(wire
		(pts
			(xy 189.23 204.47) (xy 215.9 204.47)
		)
		(stroke
			(width 0)
			(type default)
		)
	)
	(bus
		(pts
			(xy 170.18 69.85) (xy 170.18 72.39)
		)
		(stroke
			(width 0)
			(type default)
		)
	)
	(wire
		(pts
			(xy 158.75 198.12) (xy 158.75 199.39)
		)
		(stroke
			(width 0)
			(type default)
		)
	)
	(wire
		(pts
			(xy 199.39 185.42) (xy 208.28 185.42)
		)
		(stroke
			(width 0)
			(type default)
		)
	)
	(wire
		(pts
			(xy 158.75 199.39) (xy 158.75 203.2)
		)
		(stroke
			(width 0)
			(type default)
		)
	)
	(wire
		(pts
			(xy 158.75 208.28) (xy 158.75 213.36)
		)
		(stroke
			(width 0)
			(type default)
		)
	)
	(wire
		(pts
			(xy 172.72 74.93) (xy 200.66 74.93)
		)
		(stroke
			(width 0)
			(type default)
		)
	)
	(wire
		(pts
			(xy 189.23 207.01) (xy 208.28 207.01)
		)
		(stroke
			(width 0)
			(type default)
		)
	)
	(wire
		(pts
			(xy 172.72 87.63) (xy 200.66 87.63)
		)
		(stroke
			(width 0)
			(type default)
		)
	)
	(wire
		(pts
			(xy 200.66 57.15) (xy 191.77 57.15)
		)
		(stroke
			(width 0)
			(type default)
		)
	)
	(wire
		(pts
			(xy 236.22 209.55) (xy 236.22 215.9)
		)
		(stroke
			(width 0)
			(type default)
		)
	)
	(wire
		(pts
			(xy 231.14 207.01) (xy 248.92 207.01)
		)
		(stroke
			(width 0)
			(type default)
		)
	)
	(wire
		(pts
			(xy 208.28 185.42) (xy 215.9 185.42)
		)
		(stroke
			(width 0)
			(type default)
		)
	)
	(wire
		(pts
			(xy 172.72 59.69) (xy 195.58 59.69)
		)
		(stroke
			(width 0)
			(type default)
		)
	)
	(bus
		(pts
			(xy 170.18 77.47) (xy 170.18 80.01)
		)
		(stroke
			(width 0)
			(type default)
		)
	)
	(wire
		(pts
			(xy 189.23 201.93) (xy 226.06 201.93)
		)
		(stroke
			(width 0)
			(type default)
		)
	)
	(wire
		(pts
			(xy 264.16 57.15) (xy 264.16 59.69)
		)
		(stroke
			(width 0)
			(type default)
		)
	)
	(wire
		(pts
			(xy 172.72 77.47) (xy 200.66 77.47)
		)
		(stroke
			(width 0)
			(type default)
		)
	)
	(wire
		(pts
			(xy 231.14 204.47) (xy 248.92 204.47)
		)
		(stroke
			(width 0)
			(type default)
		)
	)
	(wire
		(pts
			(xy 191.77 54.61) (xy 191.77 57.15)
		)
		(stroke
			(width 0)
			(type default)
		)
	)
	(wire
		(pts
			(xy 172.72 95.25) (xy 200.66 95.25)
		)
		(stroke
			(width 0)
			(type default)
		)
	)
	(wire
		(pts
			(xy 172.72 82.55) (xy 200.66 82.55)
		)
		(stroke
			(width 0)
			(type default)
		)
	)
	(wire
		(pts
			(xy 233.68 59.69) (xy 233.68 57.15)
		)
		(stroke
			(width 0)
			(type default)
		)
	)
	(bus
		(pts
			(xy 170.18 64.77) (xy 170.18 69.85)
		)
		(stroke
			(width 0)
			(type default)
		)
	)
	(bus
		(pts
			(xy 168.91 52.07) (xy 170.18 53.34)
		)
		(stroke
			(width 0)
			(type default)
		)
	)
	(wire
		(pts
			(xy 248.92 59.69) (xy 248.92 57.15)
		)
		(stroke
			(width 0)
			(type default)
		)
	)
	(wire
		(pts
			(xy 195.58 46.99) (xy 195.58 49.53)
		)
		(stroke
			(width 0)
			(type default)
		)
	)
	(wire
		(pts
			(xy 215.9 189.23) (xy 215.9 185.42)
		)
		(stroke
			(width 0)
			(type default)
		)
	)
	(wire
		(pts
			(xy 231.14 59.69) (xy 233.68 59.69)
		)
		(stroke
			(width 0)
			(type default)
		)
	)
	(bus
		(pts
			(xy 170.18 62.23) (xy 170.18 64.77)
		)
		(stroke
			(width 0)
			(type default)
		)
	)
	(wire
		(pts
			(xy 208.28 185.42) (xy 208.28 189.23)
		)
		(stroke
			(width 0)
			(type default)
		)
	)
	(wire
		(pts
			(xy 172.72 67.31) (xy 200.66 67.31)
		)
		(stroke
			(width 0)
			(type default)
		)
	)
	(wire
		(pts
			(xy 172.72 64.77) (xy 200.66 64.77)
		)
		(stroke
			(width 0)
			(type default)
		)
	)
	(bus
		(pts
			(xy 251.46 207.01) (xy 251.46 209.55)
		)
		(stroke
			(width 0)
			(type default)
		)
	)
	(wire
		(pts
			(xy 168.91 212.09) (xy 167.64 212.09)
		)
		(stroke
			(width 0)
			(type default)
		)
	)
	(wire
		(pts
			(xy 264.16 66.04) (xy 264.16 64.77)
		)
		(stroke
			(width 0)
			(type default)
		)
	)
	(wire
		(pts
			(xy 195.58 59.69) (xy 200.66 59.69)
		)
		(stroke
			(width 0)
			(type default)
		)
	)
	(wire
		(pts
			(xy 256.54 57.15) (xy 256.54 59.69)
		)
		(stroke
			(width 0)
			(type default)
		)
	)
	(bus
		(pts
			(xy 170.18 72.39) (xy 170.18 74.93)
		)
		(stroke
			(width 0)
			(type default)
		)
	)
	(wire
		(pts
			(xy 248.92 57.15) (xy 256.54 57.15)
		)
		(stroke
			(width 0)
			(type default)
		)
	)
	(wire
		(pts
			(xy 191.77 46.99) (xy 191.77 49.53)
		)
		(stroke
			(width 0)
			(type default)
		)
	)
	(wire
		(pts
			(xy 189.23 212.09) (xy 199.39 212.09)
		)
		(stroke
			(width 0)
			(type default)
		)
	)
	(wire
		(pts
			(xy 172.72 72.39) (xy 200.66 72.39)
		)
		(stroke
			(width 0)
			(type default)
		)
	)
	(wire
		(pts
			(xy 233.68 95.25) (xy 233.68 97.79)
		)
		(stroke
			(width 0)
			(type default)
		)
	)
	(bus
		(pts
			(xy 251.46 196.85) (xy 251.46 199.39)
		)
		(stroke
			(width 0)
			(type default)
		)
	)
	(bus
		(pts
			(xy 251.46 204.47) (xy 251.46 207.01)
		)
		(stroke
			(width 0)
			(type default)
		)
	)
	(bus
		(pts
			(xy 251.46 201.93) (xy 251.46 204.47)
		)
		(stroke
			(width 0)
			(type default)
		)
	)
	(wire
		(pts
			(xy 189.23 209.55) (xy 236.22 209.55)
		)
		(stroke
			(width 0)
			(type default)
		)
	)
	(wire
		(pts
			(xy 248.92 66.04) (xy 248.92 64.77)
		)
		(stroke
			(width 0)
			(type default)
		)
	)
	(wire
		(pts
			(xy 199.39 185.42) (xy 199.39 189.23)
		)
		(stroke
			(width 0)
			(type default)
		)
	)
	(wire
		(pts
			(xy 231.14 199.39) (xy 248.92 199.39)
		)
		(stroke
			(width 0)
			(type default)
		)
	)
	(wire
		(pts
			(xy 172.72 57.15) (xy 191.77 57.15)
		)
		(stroke
			(width 0)
			(type default)
		)
	)
	(wire
		(pts
			(xy 236.22 223.52) (xy 236.22 220.98)
		)
		(stroke
			(width 0)
			(type default)
		)
	)
	(wire
		(pts
			(xy 208.28 207.01) (xy 208.28 194.31)
		)
		(stroke
			(width 0)
			(type default)
		)
	)
	(wire
		(pts
			(xy 191.77 46.99) (xy 195.58 46.99)
		)
		(stroke
			(width 0)
			(type default)
		)
	)
	(wire
		(pts
			(xy 231.14 92.71) (xy 233.68 92.71)
		)
		(stroke
			(width 0)
			(type default)
		)
	)
	(wire
		(pts
			(xy 233.68 92.71) (xy 233.68 95.25)
		)
		(stroke
			(width 0)
			(type default)
		)
	)
	(label "FLASH.IO3"
		(at 248.92 207.01 180)
		(effects
			(font
				(size 1.27 1.27)
			)
			(justify right bottom)
		)
	)
	(label "FLASH.IO1"
		(at 248.92 201.93 180)
		(effects
			(font
				(size 1.27 1.27)
			)
			(justify right bottom)
		)
	)
	(label "HyperRAM.~{CS}"
		(at 172.72 59.69 0)
		(effects
			(font
				(size 1.27 1.27)
			)
			(justify left bottom)
		)
	)
	(label "FLASH.IO2"
		(at 248.92 204.47 180)
		(effects
			(font
				(size 1.27 1.27)
			)
			(justify right bottom)
		)
	)
	(label "FLASH.~{CS}"
		(at 248.92 212.09 180)
		(effects
			(font
				(size 1.27 1.27)
			)
			(justify right bottom)
		)
	)
	(label "HyperRAM.DQ3"
		(at 172.72 80.01 0)
		(effects
			(font
				(size 1.27 1.27)
			)
			(justify left bottom)
		)
	)
	(label "HyperRAM.DQ7"
		(at 172.72 90.17 0)
		(effects
			(font
				(size 1.27 1.27)
			)
			(justify left bottom)
		)
	)
	(label "IO3"
		(at 193.04 207.01 180)
		(effects
			(font
				(size 1.27 1.27)
			)
			(justify right bottom)
		)
	)
	(label "HyperRAM.~{RESET}"
		(at 172.72 57.15 0)
		(effects
			(font
				(size 1.27 1.27)
			)
			(justify left bottom)
		)
	)
	(label "HyperRAM.DQ1"
		(at 172.72 74.93 0)
		(effects
			(font
				(size 1.27 1.27)
			)
			(justify left bottom)
		)
	)
	(label "FLASH.IO0"
		(at 248.92 199.39 180)
		(effects
			(font
				(size 1.27 1.27)
			)
			(justify right bottom)
		)
	)
	(label "IO1"
		(at 193.04 201.93 180)
		(effects
			(font
				(size 1.27 1.27)
			)
			(justify right bottom)
		)
	)
	(label "HyperRAM.DQ2"
		(at 172.72 77.47 0)
		(effects
			(font
				(size 1.27 1.27)
			)
			(justify left bottom)
		)
	)
	(label "HyperRAM.DQ5"
		(at 172.72 85.09 0)
		(effects
			(font
				(size 1.27 1.27)
			)
			(justify left bottom)
		)
	)
	(label "HyperRAM.RWDS"
		(at 172.72 95.25 0)
		(effects
			(font
				(size 1.27 1.27)
			)
			(justify left bottom)
		)
	)
	(label "HyperRAM.DQ0"
		(at 172.72 72.39 0)
		(effects
			(font
				(size 1.27 1.27)
			)
			(justify left bottom)
		)
	)
	(label "HyperRAM.DQ6"
		(at 172.72 87.63 0)
		(effects
			(font
				(size 1.27 1.27)
			)
			(justify left bottom)
		)
	)
	(label "IO0"
		(at 193.04 199.39 180)
		(effects
			(font
				(size 1.27 1.27)
			)
			(justify right bottom)
		)
	)
	(label "HyperRAM.CK_P"
		(at 172.72 64.77 0)
		(effects
			(font
				(size 1.27 1.27)
			)
			(justify left bottom)
		)
	)
	(label "HyperRAM.DQ4"
		(at 172.72 82.55 0)
		(effects
			(font
				(size 1.27 1.27)
			)
			(justify left bottom)
		)
	)
	(label "IO2"
		(at 193.04 204.47 180)
		(effects
			(font
				(size 1.27 1.27)
			)
			(justify right bottom)
		)
	)
	(label "FLASH.SCK"
		(at 248.92 209.55 180)
		(effects
			(font
				(size 1.27 1.27)
			)
			(justify right bottom)
		)
	)
	(label "HyperRAM.CK_N"
		(at 172.72 67.31 0)
		(effects
			(font
				(size 1.27 1.27)
			)
			(justify left bottom)
		)
	)
	(hierarchical_label "FLASH{QSPI}"
		(shape bidirectional)
		(at 255.27 194.31 0)
		(effects
			(font
				(size 1.27 1.27)
			)
			(justify left)
		)
	)
	(hierarchical_label "HyperRAM{HyperBus}"
		(shape bidirectional)
		(at 167.64 52.07 180)
		(effects
			(font
				(size 1.27 1.27)
			)
			(justify right)
		)
	)
	(symbol
		(lib_id "antmicroCapacitors0603:C_47u_0603")
		(at 240.03 59.69 270)
		(unit 1)
		(exclude_from_sim no)
		(in_bom yes)
		(on_board yes)
		(dnp no)
		(property "Reference" "C1"
			(at 240.665 60.325 90)
			(effects
				(font
					(size 1.27 1.27)
				)
				(justify left)
			)
		)
		(property "Value" "C_47u_0603"
			(at 229.87 80.01 0)
			(effects
				(font
					(size 1.27 1.27)
					(thickness 0.15)
				)
				(justify left bottom)
				(hide yes)
			)
		)
		(property "Footprint" "antmicro-footprints:C_0603_1608Metric"
			(at 227.33 80.01 0)
			(effects
				(font
					(size 1.27 1.27)
					(thickness 0.15)
				)
				(justify left bottom)
				(hide yes)
			)
		)
		(property "Datasheet" "https://www.murata.com/products/productdetail?partno=GRM188R60J476ME15%23"
			(at 224.79 80.01 0)
			(effects
				(font
					(size 1.27 1.27)
					(thickness 0.15)
				)
				(justify left bottom)
				(hide yes)
			)
		)
		(property "Description" ""
			(at 240.03 59.69 0)
			(effects
				(font
					(size 1.27 1.27)
				)
				(hide yes)
			)
		)
		(property "Manufacturer" "Murata"
			(at 219.71 80.01 0)
			(effects
				(font
					(size 1.27 1.27)
					(thickness 0.15)
				)
				(justify left bottom)
				(hide yes)
			)
		)
		(property "MPN" "GRM188R60J476ME15D"
			(at 222.25 80.01 0)
			(effects
				(font
					(size 1.27 1.27)
					(thickness 0.15)
				)
				(justify left bottom)
				(hide yes)
			)
		)
		(property "Val" "47u"
			(at 240.665 64.135 90)
			(effects
				(font
					(size 1.27 1.27)
					(thickness 0.15)
				)
				(justify left)
			)
		)
		(property "License" "Apache-2.0"
			(at 217.17 80.01 0)
			(effects
				(font
					(size 1.27 1.27)
					(thickness 0.15)
				)
				(justify left bottom)
				(hide yes)
			)
		)
		(property "Author" "Antmicro"
			(at 214.63 80.01 0)
			(effects
				(font
					(size 1.27 1.27)
					(thickness 0.15)
				)
				(justify left bottom)
				(hide yes)
			)
		)
		(property "Voltage" ""
			(at 212.09 80.01 0)
			(effects
				(font
					(size 1.27 1.27)
				)
				(justify left bottom)
				(hide yes)
			)
		)
		(property "Dielectric" ""
			(at 209.55 80.01 0)
			(effects
				(font
					(size 1.27 1.27)
				)
				(justify left bottom)
				(hide yes)
			)
		)
		(pin "1"
		)
		(pin "2"
		)
		(instances
			(project "data-center-rdimm-ddr5-tester"
				(path ""
					(reference "C1")
					(unit 1)
				)
			)
		)
	)
	(symbol
		(lib_id "antmicroCapacitors0402:C_100n_0402")
		(at 256.54 59.69 270)
		(unit 1)
		(exclude_from_sim no)
		(in_bom yes)
		(on_board yes)
		(dnp no)
		(property "Reference" "C3"
			(at 257.175 60.325 90)
			(effects
				(font
					(size 1.27 1.27)
				)
				(justify left)
			)
		)
		(property "Value" "C_100n_0402"
			(at 246.38 80.01 0)
			(effects
				(font
					(size 1.27 1.27)
					(thickness 0.15)
				)
				(justify left bottom)
				(hide yes)
			)
		)
		(property "Footprint" "antmicro-footprints:C_0402_1005Metric"
			(at 243.84 80.01 0)
			(effects
				(font
					(size 1.27 1.27)
					(thickness 0.15)
				)
				(justify left bottom)
				(hide yes)
			)
		)
		(property "Datasheet" "https://www.murata.com/products/productdetail?partno=GRM155R61H104KE14%23"
			(at 241.3 80.01 0)
			(effects
				(font
					(size 1.27 1.27)
					(thickness 0.15)
				)
				(justify left bottom)
				(hide yes)
			)
		)
		(property "Description" ""
			(at 256.54 59.69 0)
			(effects
				(font
					(size 1.27 1.27)
				)
				(hide yes)
			)
		)
		(property "Manufacturer" "Murata"
			(at 236.22 80.01 0)
			(effects
				(font
					(size 1.27 1.27)
					(thickness 0.15)
				)
				(justify left bottom)
				(hide yes)
			)
		)
		(property "MPN" "GRM155R61H104KE14D"
			(at 238.76 80.01 0)
			(effects
				(font
					(size 1.27 1.27)
					(thickness 0.15)
				)
				(justify left bottom)
				(hide yes)
			)
		)
		(property "Val" "100n"
			(at 257.175 64.135 90)
			(effects
				(font
					(size 1.27 1.27)
					(thickness 0.15)
				)
				(justify left)
			)
		)
		(property "License" "Apache-2.0"
			(at 233.68 80.01 0)
			(effects
				(font
					(size 1.27 1.27)
					(thickness 0.15)
				)
				(justify left bottom)
				(hide yes)
			)
		)
		(property "Author" "Antmicro"
			(at 231.14 80.01 0)
			(effects
				(font
					(size 1.27 1.27)
					(thickness 0.15)
				)
				(justify left bottom)
				(hide yes)
			)
		)
		(property "Voltage" "50V"
			(at 228.6 80.01 0)
			(effects
				(font
					(size 1.27 1.27)
				)
				(justify left bottom)
				(hide yes)
			)
		)
		(property "Dielectric" "X5R"
			(at 226.06 80.01 0)
			(effects
				(font
					(size 1.27 1.27)
				)
				(justify left bottom)
				(hide yes)
			)
		)
		(pin "1"
		)
		(pin "2"
		)
		(instances
			(project "data-center-rdimm-ddr5-tester"
				(path ""
					(reference "C3")
					(unit 1)
				)
			)
		)
	)
	(symbol
		(lib_id "antmicropower:GND")
		(at 240.03 66.04 0)
		(unit 1)
		(exclude_from_sim no)
		(in_bom yes)
		(on_board yes)
		(dnp no)
		(fields_autoplaced yes)
		(property "Reference" "#PWR04"
			(at 240.03 72.39 0)
			(effects
				(font
					(size 1.27 1.27)
				)
				(hide yes)
			)
		)
		(property "Value" "GND"
			(at 238.125 70.485 0)
			(effects
				(font
					(size 1.27 1.27)
					(thickness 0.15)
				)
				(justify left bottom)
			)
		)
		(property "Footprint" ""
			(at 248.92 73.66 0)
			(effects
				(font
					(size 1.27 1.27)
					(thickness 0.15)
				)
				(justify left bottom)
				(hide yes)
			)
		)
		(property "Datasheet" ""
			(at 248.92 78.74 0)
			(effects
				(font
					(size 1.27 1.27)
					(thickness 0.15)
				)
				(justify left bottom)
				(hide yes)
			)
		)
		(property "Description" ""
			(at 240.03 66.04 0)
			(effects
				(font
					(size 1.27 1.27)
				)
				(hide yes)
			)
		)
		(property "Author" "Antmicro"
			(at 248.92 71.12 0)
			(effects
				(font
					(size 1.27 1.27)
					(thickness 0.15)
				)
				(justify left bottom)
				(hide yes)
			)
		)
		(property "License" "Apache-2.0"
			(at 248.92 73.66 0)
			(effects
				(font
					(size 1.27 1.27)
					(thickness 0.15)
				)
				(justify left bottom)
				(hide yes)
			)
		)
		(pin "1"
		)
		(instances
			(project "data-center-rdimm-ddr5-tester"
				(path ""
					(reference "#PWR04")
					(unit 1)
				)
			)
		)
	)
	(symbol
		(lib_id "antmicroResistors0402:R_10k_0402")
		(at 191.77 49.53 270)
		(unit 1)
		(exclude_from_sim no)
		(in_bom yes)
		(on_board yes)
		(dnp no)
		(property "Reference" "R1"
			(at 189.865 50.8001 90)
			(effects
				(font
					(size 1.27 1.27)
				)
				(justify right)
			)
		)
		(property "Value" "R_10k_0402"
			(at 179.07 69.85 0)
			(effects
				(font
					(size 1.27 1.27)
					(thickness 0.15)
				)
				(justify left bottom)
				(hide yes)
			)
		)
		(property "Footprint" "antmicro-footprints:R_0402_1005Metric"
			(at 176.53 69.85 0)
			(effects
				(font
					(size 1.27 1.27)
					(thickness 0.15)
				)
				(justify left bottom)
				(hide yes)
			)
		)
		(property "Datasheet" "https://www.bourns.com/docs/product-datasheets/cr.pdf"
			(at 173.99 69.85 0)
			(effects
				(font
					(size 1.27 1.27)
					(thickness 0.15)
				)
				(justify left bottom)
				(hide yes)
			)
		)
		(property "Description" ""
			(at 191.77 49.53 0)
			(effects
				(font
					(size 1.27 1.27)
				)
				(hide yes)
			)
		)
		(property "Manufacturer" "Bourns"
			(at 168.91 69.85 0)
			(effects
				(font
					(size 1.27 1.27)
					(thickness 0.15)
				)
				(justify left bottom)
				(hide yes)
			)
		)
		(property "MPN" "CR0402-FX-1002GLF"
			(at 171.45 69.85 0)
			(effects
				(font
					(size 1.27 1.27)
					(thickness 0.15)
				)
				(justify left bottom)
				(hide yes)
			)
		)
		(property "Val" "10k"
			(at 189.865 53.975 90)
			(effects
				(font
					(size 1.27 1.27)
					(thickness 0.15)
				)
				(justify right)
			)
		)
		(property "License" "Apache-2.0"
			(at 166.37 69.85 0)
			(effects
				(font
					(size 1.27 1.27)
					(thickness 0.15)
				)
				(justify left bottom)
				(hide yes)
			)
		)
		(property "Author" "Antmicro"
			(at 163.83 69.85 0)
			(effects
				(font
					(size 1.27 1.27)
					(thickness 0.15)
				)
				(justify left bottom)
				(hide yes)
			)
		)
		(property "Tolerance" "1%"
			(at 181.61 69.85 0)
			(effects
				(font
					(size 1.27 1.27)
				)
				(justify left bottom)
				(hide yes)
			)
		)
		(pin "1"
		)
		(pin "2"
		)
		(instances
			(project "data-center-rdimm-ddr5-tester"
				(path ""
					(reference "R1")
					(unit 1)
				)
			)
		)
	)
	(symbol
		(lib_id "antmicropower:GND")
		(at 248.92 66.04 0)
		(unit 1)
		(exclude_from_sim no)
		(in_bom yes)
		(on_board yes)
		(dnp no)
		(fields_autoplaced yes)
		(property "Reference" "#PWR05"
			(at 248.92 72.39 0)
			(effects
				(font
					(size 1.27 1.27)
				)
				(hide yes)
			)
		)
		(property "Value" "GND"
			(at 247.015 70.485 0)
			(effects
				(font
					(size 1.27 1.27)
					(thickness 0.15)
				)
				(justify left bottom)
			)
		)
		(property "Footprint" ""
			(at 257.81 73.66 0)
			(effects
				(font
					(size 1.27 1.27)
					(thickness 0.15)
				)
				(justify left bottom)
				(hide yes)
			)
		)
		(property "Datasheet" ""
			(at 257.81 78.74 0)
			(effects
				(font
					(size 1.27 1.27)
					(thickness 0.15)
				)
				(justify left bottom)
				(hide yes)
			)
		)
		(property "Description" ""
			(at 248.92 66.04 0)
			(effects
				(font
					(size 1.27 1.27)
				)
				(hide yes)
			)
		)
		(property "Author" "Antmicro"
			(at 257.81 71.12 0)
			(effects
				(font
					(size 1.27 1.27)
					(thickness 0.15)
				)
				(justify left bottom)
				(hide yes)
			)
		)
		(property "License" "Apache-2.0"
			(at 257.81 73.66 0)
			(effects
				(font
					(size 1.27 1.27)
					(thickness 0.15)
				)
				(justify left bottom)
				(hide yes)
			)
		)
		(pin "1"
		)
		(instances
			(project "data-center-rdimm-ddr5-tester"
				(path ""
					(reference "#PWR05")
					(unit 1)
				)
			)
		)
	)
	(symbol
		(lib_id "antmicropower:GND")
		(at 256.54 66.04 0)
		(unit 1)
		(exclude_from_sim no)
		(in_bom yes)
		(on_board yes)
		(dnp no)
		(fields_autoplaced yes)
		(property "Reference" "#PWR06"
			(at 256.54 72.39 0)
			(effects
				(font
					(size 1.27 1.27)
				)
				(hide yes)
			)
		)
		(property "Value" "GND"
			(at 254.635 70.485 0)
			(effects
				(font
					(size 1.27 1.27)
					(thickness 0.15)
				)
				(justify left bottom)
			)
		)
		(property "Footprint" ""
			(at 265.43 73.66 0)
			(effects
				(font
					(size 1.27 1.27)
					(thickness 0.15)
				)
				(justify left bottom)
				(hide yes)
			)
		)
		(property "Datasheet" ""
			(at 265.43 78.74 0)
			(effects
				(font
					(size 1.27 1.27)
					(thickness 0.15)
				)
				(justify left bottom)
				(hide yes)
			)
		)
		(property "Description" ""
			(at 256.54 66.04 0)
			(effects
				(font
					(size 1.27 1.27)
				)
				(hide yes)
			)
		)
		(property "Author" "Antmicro"
			(at 265.43 71.12 0)
			(effects
				(font
					(size 1.27 1.27)
					(thickness 0.15)
				)
				(justify left bottom)
				(hide yes)
			)
		)
		(property "License" "Apache-2.0"
			(at 265.43 73.66 0)
			(effects
				(font
					(size 1.27 1.27)
					(thickness 0.15)
				)
				(justify left bottom)
				(hide yes)
			)
		)
		(pin "1"
		)
		(instances
			(project "data-center-rdimm-ddr5-tester"
				(path ""
					(reference "#PWR06")
					(unit 1)
				)
			)
		)
	)
	(symbol
		(lib_id "antmicroCapacitors0402:C_100n_0402")
		(at 248.92 59.69 270)
		(unit 1)
		(exclude_from_sim no)
		(in_bom yes)
		(on_board yes)
		(dnp no)
		(property "Reference" "C2"
			(at 249.555 60.325 90)
			(effects
				(font
					(size 1.27 1.27)
				)
				(justify left)
			)
		)
		(property "Value" "C_100n_0402"
			(at 238.76 80.01 0)
			(effects
				(font
					(size 1.27 1.27)
					(thickness 0.15)
				)
				(justify left bottom)
				(hide yes)
			)
		)
		(property "Footprint" "antmicro-footprints:C_0402_1005Metric"
			(at 236.22 80.01 0)
			(effects
				(font
					(size 1.27 1.27)
					(thickness 0.15)
				)
				(justify left bottom)
				(hide yes)
			)
		)
		(property "Datasheet" "https://www.murata.com/products/productdetail?partno=GRM155R61H104KE14%23"
			(at 233.68 80.01 0)
			(effects
				(font
					(size 1.27 1.27)
					(thickness 0.15)
				)
				(justify left bottom)
				(hide yes)
			)
		)
		(property "Description" ""
			(at 248.92 59.69 0)
			(effects
				(font
					(size 1.27 1.27)
				)
				(hide yes)
			)
		)
		(property "Manufacturer" "Murata"
			(at 228.6 80.01 0)
			(effects
				(font
					(size 1.27 1.27)
					(thickness 0.15)
				)
				(justify left bottom)
				(hide yes)
			)
		)
		(property "MPN" "GRM155R61H104KE14D"
			(at 231.14 80.01 0)
			(effects
				(font
					(size 1.27 1.27)
					(thickness 0.15)
				)
				(justify left bottom)
				(hide yes)
			)
		)
		(property "Val" "100n"
			(at 249.555 64.135 90)
			(effects
				(font
					(size 1.27 1.27)
					(thickness 0.15)
				)
				(justify left)
			)
		)
		(property "License" "Apache-2.0"
			(at 226.06 80.01 0)
			(effects
				(font
					(size 1.27 1.27)
					(thickness 0.15)
				)
				(justify left bottom)
				(hide yes)
			)
		)
		(property "Author" "Antmicro"
			(at 223.52 80.01 0)
			(effects
				(font
					(size 1.27 1.27)
					(thickness 0.15)
				)
				(justify left bottom)
				(hide yes)
			)
		)
		(property "Voltage" "50V"
			(at 220.98 80.01 0)
			(effects
				(font
					(size 1.27 1.27)
				)
				(justify left bottom)
				(hide yes)
			)
		)
		(property "Dielectric" "X5R"
			(at 218.44 80.01 0)
			(effects
				(font
					(size 1.27 1.27)
				)
				(justify left bottom)
				(hide yes)
			)
		)
		(pin "1"
		)
		(pin "2"
		)
		(instances
			(project "data-center-rdimm-ddr5-tester"
				(path ""
					(reference "C2")
					(unit 1)
				)
			)
		)
	)
	(symbol
		(lib_id "antmicroResistors0402:R_10k_0402")
		(at 195.58 49.53 270)
		(unit 1)
		(exclude_from_sim no)
		(in_bom yes)
		(on_board yes)
		(dnp no)
		(fields_autoplaced yes)
		(property "Reference" "R2"
			(at 197.485 50.8 90)
			(effects
				(font
					(size 1.27 1.27)
				)
				(justify left)
			)
		)
		(property "Value" "R_10k_0402"
			(at 182.88 69.85 0)
			(effects
				(font
					(size 1.27 1.27)
					(thickness 0.15)
				)
				(justify left bottom)
				(hide yes)
			)
		)
		(property "Footprint" "antmicro-footprints:R_0402_1005Metric"
			(at 180.34 69.85 0)
			(effects
				(font
					(size 1.27 1.27)
					(thickness 0.15)
				)
				(justify left bottom)
				(hide yes)
			)
		)
		(property "Datasheet" "https://www.bourns.com/docs/product-datasheets/cr.pdf"
			(at 177.8 69.85 0)
			(effects
				(font
					(size 1.27 1.27)
					(thickness 0.15)
				)
				(justify left bottom)
				(hide yes)
			)
		)
		(property "Description" ""
			(at 195.58 49.53 0)
			(effects
				(font
					(size 1.27 1.27)
				)
				(hide yes)
			)
		)
		(property "Manufacturer" "Bourns"
			(at 172.72 69.85 0)
			(effects
				(font
					(size 1.27 1.27)
					(thickness 0.15)
				)
				(justify left bottom)
				(hide yes)
			)
		)
		(property "MPN" "CR0402-FX-1002GLF"
			(at 175.26 69.85 0)
			(effects
				(font
					(size 1.27 1.27)
					(thickness 0.15)
				)
				(justify left bottom)
				(hide yes)
			)
		)
		(property "Val" "10k"
			(at 197.485 53.9749 90)
			(effects
				(font
					(size 1.27 1.27)
					(thickness 0.15)
				)
				(justify left)
			)
		)
		(property "License" "Apache-2.0"
			(at 170.18 69.85 0)
			(effects
				(font
					(size 1.27 1.27)
					(thickness 0.15)
				)
				(justify left bottom)
				(hide yes)
			)
		)
		(property "Author" "Antmicro"
			(at 167.64 69.85 0)
			(effects
				(font
					(size 1.27 1.27)
					(thickness 0.15)
				)
				(justify left bottom)
				(hide yes)
			)
		)
		(property "Tolerance" "1%"
			(at 185.42 69.85 0)
			(effects
				(font
					(size 1.27 1.27)
				)
				(justify left bottom)
				(hide yes)
			)
		)
		(pin "1"
		)
		(pin "2"
		)
		(instances
			(project "data-center-rdimm-ddr5-tester"
				(path ""
					(reference "R2")
					(unit 1)
				)
			)
		)
	)
	(symbol
		(lib_id "antmicropower:GND")
		(at 233.68 97.79 0)
		(unit 1)
		(exclude_from_sim no)
		(in_bom yes)
		(on_board yes)
		(dnp no)
		(fields_autoplaced yes)
		(property "Reference" "#PWR03"
			(at 233.68 104.14 0)
			(effects
				(font
					(size 1.27 1.27)
				)
				(hide yes)
			)
		)
		(property "Value" "GND"
			(at 231.775 102.235 0)
			(effects
				(font
					(size 1.27 1.27)
					(thickness 0.15)
				)
				(justify left bottom)
			)
		)
		(property "Footprint" ""
			(at 242.57 105.41 0)
			(effects
				(font
					(size 1.27 1.27)
					(thickness 0.15)
				)
				(justify left bottom)
				(hide yes)
			)
		)
		(property "Datasheet" ""
			(at 242.57 110.49 0)
			(effects
				(font
					(size 1.27 1.27)
					(thickness 0.15)
				)
				(justify left bottom)
				(hide yes)
			)
		)
		(property "Description" ""
			(at 233.68 97.79 0)
			(effects
				(font
					(size 1.27 1.27)
				)
				(hide yes)
			)
		)
		(property "Author" "Antmicro"
			(at 242.57 102.87 0)
			(effects
				(font
					(size 1.27 1.27)
					(thickness 0.15)
				)
				(justify left bottom)
				(hide yes)
			)
		)
		(property "License" "Apache-2.0"
			(at 242.57 105.41 0)
			(effects
				(font
					(size 1.27 1.27)
					(thickness 0.15)
				)
				(justify left bottom)
				(hide yes)
			)
		)
		(pin "1"
		)
		(instances
			(project "data-center-rdimm-ddr5-tester"
				(path ""
					(reference "#PWR03")
					(unit 1)
				)
			)
		)
	)
	(symbol
		(lib_id "antmicroCapacitors0402:C_100n_0402")
		(at 264.16 59.69 270)
		(unit 1)
		(exclude_from_sim no)
		(in_bom yes)
		(on_board yes)
		(dnp no)
		(property "Reference" "C4"
			(at 264.795 60.325 90)
			(effects
				(font
					(size 1.27 1.27)
				)
				(justify left)
			)
		)
		(property "Value" "C_100n_0402"
			(at 254 80.01 0)
			(effects
				(font
					(size 1.27 1.27)
					(thickness 0.15)
				)
				(justify left bottom)
				(hide yes)
			)
		)
		(property "Footprint" "antmicro-footprints:C_0402_1005Metric"
			(at 251.46 80.01 0)
			(effects
				(font
					(size 1.27 1.27)
					(thickness 0.15)
				)
				(justify left bottom)
				(hide yes)
			)
		)
		(property "Datasheet" "https://www.murata.com/products/productdetail?partno=GRM155R61H104KE14%23"
			(at 248.92 80.01 0)
			(effects
				(font
					(size 1.27 1.27)
					(thickness 0.15)
				)
				(justify left bottom)
				(hide yes)
			)
		)
		(property "Description" ""
			(at 264.16 59.69 0)
			(effects
				(font
					(size 1.27 1.27)
				)
				(hide yes)
			)
		)
		(property "Manufacturer" "Murata"
			(at 243.84 80.01 0)
			(effects
				(font
					(size 1.27 1.27)
					(thickness 0.15)
				)
				(justify left bottom)
				(hide yes)
			)
		)
		(property "MPN" "GRM155R61H104KE14D"
			(at 246.38 80.01 0)
			(effects
				(font
					(size 1.27 1.27)
					(thickness 0.15)
				)
				(justify left bottom)
				(hide yes)
			)
		)
		(property "Val" "100n"
			(at 264.795 64.135 90)
			(effects
				(font
					(size 1.27 1.27)
					(thickness 0.15)
				)
				(justify left)
			)
		)
		(property "License" "Apache-2.0"
			(at 241.3 80.01 0)
			(effects
				(font
					(size 1.27 1.27)
					(thickness 0.15)
				)
				(justify left bottom)
				(hide yes)
			)
		)
		(property "Author" "Antmicro"
			(at 238.76 80.01 0)
			(effects
				(font
					(size 1.27 1.27)
					(thickness 0.15)
				)
				(justify left bottom)
				(hide yes)
			)
		)
		(property "Voltage" "50V"
			(at 236.22 80.01 0)
			(effects
				(font
					(size 1.27 1.27)
				)
				(justify left bottom)
				(hide yes)
			)
		)
		(property "Dielectric" "X5R"
			(at 233.68 80.01 0)
			(effects
				(font
					(size 1.27 1.27)
				)
				(justify left bottom)
				(hide yes)
			)
		)
		(pin "1"
		)
		(pin "2"
		)
		(instances
			(project "data-center-rdimm-ddr5-tester"
				(path ""
					(reference "C4")
					(unit 1)
				)
			)
		)
	)
	(symbol
		(lib_id "antmicropower:GND")
		(at 264.16 66.04 0)
		(unit 1)
		(exclude_from_sim no)
		(in_bom yes)
		(on_board yes)
		(dnp no)
		(fields_autoplaced yes)
		(property "Reference" "#PWR07"
			(at 264.16 72.39 0)
			(effects
				(font
					(size 1.27 1.27)
				)
				(hide yes)
			)
		)
		(property "Value" "GND"
			(at 262.255 70.485 0)
			(effects
				(font
					(size 1.27 1.27)
					(thickness 0.15)
				)
				(justify left bottom)
			)
		)
		(property "Footprint" ""
			(at 273.05 73.66 0)
			(effects
				(font
					(size 1.27 1.27)
					(thickness 0.15)
				)
				(justify left bottom)
				(hide yes)
			)
		)
		(property "Datasheet" ""
			(at 273.05 78.74 0)
			(effects
				(font
					(size 1.27 1.27)
					(thickness 0.15)
				)
				(justify left bottom)
				(hide yes)
			)
		)
		(property "Description" ""
			(at 264.16 66.04 0)
			(effects
				(font
					(size 1.27 1.27)
				)
				(hide yes)
			)
		)
		(property "Author" "Antmicro"
			(at 273.05 71.12 0)
			(effects
				(font
					(size 1.27 1.27)
					(thickness 0.15)
				)
				(justify left bottom)
				(hide yes)
			)
		)
		(property "License" "Apache-2.0"
			(at 273.05 73.66 0)
			(effects
				(font
					(size 1.27 1.27)
					(thickness 0.15)
				)
				(justify left bottom)
				(hide yes)
			)
		)
		(pin "1"
		)
		(instances
			(project "data-center-rdimm-ddr5-tester"
				(path ""
					(reference "#PWR07")
					(unit 1)
				)
			)
		)
	)
	(symbol
		(lib_id "antmicroResistors0402:R_22R_0402")
		(at 226.06 201.93 0)
		(unit 1)
		(exclude_from_sim no)
		(in_bom yes)
		(on_board yes)
		(dnp no)
		(property "Reference" "R7"
			(at 232.41 200.66 0)
			(effects
				(font
					(size 1.27 1.27)
				)
			)
		)
		(property "Value" "R_22R_0402"
			(at 246.38 214.63 0)
			(effects
				(font
					(size 1.27 1.27)
					(thickness 0.15)
				)
				(justify left bottom)
				(hide yes)
			)
		)
		(property "Footprint" "antmicro-footprints:R_0402_1005Metric"
			(at 246.38 217.17 0)
			(effects
				(font
					(size 1.27 1.27)
					(thickness 0.15)
				)
				(justify left bottom)
				(hide yes)
			)
		)
		(property "Datasheet" "https://www.bourns.com/docs/product-datasheets/cr.pdf"
			(at 246.38 219.71 0)
			(effects
				(font
					(size 1.27 1.27)
					(thickness 0.15)
				)
				(justify left bottom)
				(hide yes)
			)
		)
		(property "Description" ""
			(at 226.06 201.93 0)
			(effects
				(font
					(size 1.27 1.27)
				)
				(hide yes)
			)
		)
		(property "Manufacturer" "Bourns"
			(at 246.38 224.79 0)
			(effects
				(font
					(size 1.27 1.27)
					(thickness 0.15)
				)
				(justify left bottom)
				(hide yes)
			)
		)
		(property "MPN" "CR0402-FX-22R0GLF"
			(at 246.38 222.25 0)
			(effects
				(font
					(size 1.27 1.27)
					(thickness 0.15)
				)
				(justify left bottom)
				(hide yes)
			)
		)
		(property "Val" "22R"
			(at 224.155 200.66 0)
			(effects
				(font
					(size 1.27 1.27)
					(thickness 0.15)
				)
			)
		)
		(property "License" "Apache-2.0"
			(at 246.38 227.33 0)
			(effects
				(font
					(size 1.27 1.27)
					(thickness 0.15)
				)
				(justify left bottom)
				(hide yes)
			)
		)
		(property "Author" "Antmicro"
			(at 246.38 229.87 0)
			(effects
				(font
					(size 1.27 1.27)
					(thickness 0.15)
				)
				(justify left bottom)
				(hide yes)
			)
		)
		(property "Tolerance" "1%"
			(at 246.38 212.09 0)
			(effects
				(font
					(size 1.27 1.27)
				)
				(justify left bottom)
				(hide yes)
			)
		)
		(pin "1"
		)
		(pin "2"
		)
		(instances
			(project "data-center-rdimm-ddr5-tester"
				(path ""
					(reference "R7")
					(unit 1)
				)
			)
		)
	)
	(symbol
		(lib_id "antmicropower:+1V8")
		(at 158.75 198.12 0)
		(unit 1)
		(exclude_from_sim no)
		(in_bom yes)
		(on_board yes)
		(dnp no)
		(fields_autoplaced yes)
		(property "Reference" "#PWR0274"
			(at 173.99 200.66 0)
			(effects
				(font
					(size 1.27 1.27)
					(thickness 0.15)
				)
				(justify left bottom)
				(hide yes)
			)
		)
		(property "Value" "+1V8"
			(at 158.75 193.675 0)
			(effects
				(font
					(size 1.27 1.27)
					(thickness 0.15)
				)
			)
		)
		(property "Footprint" ""
			(at 173.99 205.74 0)
			(effects
				(font
					(size 1.27 1.27)
					(thickness 0.15)
				)
				(justify left bottom)
				(hide yes)
			)
		)
		(property "Datasheet" ""
			(at 173.99 208.28 0)
			(effects
				(font
					(size 1.27 1.27)
					(thickness 0.15)
				)
				(justify left bottom)
				(hide yes)
			)
		)
		(property "Description" ""
			(at 158.75 198.12 0)
			(effects
				(font
					(size 1.27 1.27)
				)
				(hide yes)
			)
		)
		(property "Author" "Antmicro"
			(at 173.99 203.2 0)
			(effects
				(font
					(size 1.27 1.27)
					(thickness 0.15)
				)
				(justify left bottom)
				(hide yes)
			)
		)
		(property "License" "Apache-2.0"
			(at 173.99 205.74 0)
			(effects
				(font
					(size 1.27 1.27)
					(thickness 0.15)
				)
				(justify left bottom)
				(hide yes)
			)
		)
		(pin "1"
		)
		(instances
			(project "data-center-rdimm-ddr5-tester"
				(path ""
					(reference "#PWR0274")
					(unit 1)
				)
			)
		)
	)
	(symbol
		(lib_id "antmicroResistors0402:R_22R_0402")
		(at 226.06 204.47 0)
		(unit 1)
		(exclude_from_sim no)
		(in_bom yes)
		(on_board yes)
		(dnp no)
		(property "Reference" "R8"
			(at 232.41 203.2 0)
			(effects
				(font
					(size 1.27 1.27)
				)
			)
		)
		(property "Value" "R_22R_0402"
			(at 246.38 217.17 0)
			(effects
				(font
					(size 1.27 1.27)
					(thickness 0.15)
				)
				(justify left bottom)
				(hide yes)
			)
		)
		(property "Footprint" "antmicro-footprints:R_0402_1005Metric"
			(at 246.38 219.71 0)
			(effects
				(font
					(size 1.27 1.27)
					(thickness 0.15)
				)
				(justify left bottom)
				(hide yes)
			)
		)
		(property "Datasheet" "https://www.bourns.com/docs/product-datasheets/cr.pdf"
			(at 246.38 222.25 0)
			(effects
				(font
					(size 1.27 1.27)
					(thickness 0.15)
				)
				(justify left bottom)
				(hide yes)
			)
		)
		(property "Description" ""
			(at 226.06 204.47 0)
			(effects
				(font
					(size 1.27 1.27)
				)
				(hide yes)
			)
		)
		(property "Manufacturer" "Bourns"
			(at 246.38 227.33 0)
			(effects
				(font
					(size 1.27 1.27)
					(thickness 0.15)
				)
				(justify left bottom)
				(hide yes)
			)
		)
		(property "MPN" "CR0402-FX-22R0GLF"
			(at 246.38 224.79 0)
			(effects
				(font
					(size 1.27 1.27)
					(thickness 0.15)
				)
				(justify left bottom)
				(hide yes)
			)
		)
		(property "Val" "22R"
			(at 224.155 203.2 0)
			(effects
				(font
					(size 1.27 1.27)
					(thickness 0.15)
				)
			)
		)
		(property "License" "Apache-2.0"
			(at 246.38 229.87 0)
			(effects
				(font
					(size 1.27 1.27)
					(thickness 0.15)
				)
				(justify left bottom)
				(hide yes)
			)
		)
		(property "Author" "Antmicro"
			(at 246.38 232.41 0)
			(effects
				(font
					(size 1.27 1.27)
					(thickness 0.15)
				)
				(justify left bottom)
				(hide yes)
			)
		)
		(property "Tolerance" "1%"
			(at 246.38 214.63 0)
			(effects
				(font
					(size 1.27 1.27)
				)
				(justify left bottom)
				(hide yes)
			)
		)
		(pin "1"
		)
		(pin "2"
		)
		(instances
			(project "data-center-rdimm-ddr5-tester"
				(path ""
					(reference "R8")
					(unit 1)
				)
			)
		)
	)
	(symbol
		(lib_id "antmicroResistors0402:R_4k7_0402")
		(at 215.9 189.23 90)
		(mirror x)
		(unit 1)
		(exclude_from_sim no)
		(in_bom yes)
		(on_board yes)
		(dnp no)
		(property "Reference" "R5"
			(at 215.9 188.595 90)
			(effects
				(font
					(size 1.27 1.27)
				)
				(justify right)
			)
		)
		(property "Value" "R_4k7_0402"
			(at 228.6 209.55 0)
			(effects
				(font
					(size 1.27 1.27)
					(thickness 0.15)
				)
				(justify left bottom)
				(hide yes)
			)
		)
		(property "Footprint" "antmicro-footprints:R_0402_1005Metric"
			(at 231.14 209.55 0)
			(effects
				(font
					(size 1.27 1.27)
					(thickness 0.15)
				)
				(justify left bottom)
				(hide yes)
			)
		)
		(property "Datasheet" "https://www.bourns.com/docs/product-datasheets/cr.pdf"
			(at 233.68 209.55 0)
			(effects
				(font
					(size 1.27 1.27)
					(thickness 0.15)
				)
				(justify left bottom)
				(hide yes)
			)
		)
		(property "Description" ""
			(at 215.9 189.23 0)
			(effects
				(font
					(size 1.27 1.27)
				)
				(hide yes)
			)
		)
		(property "Manufacturer" "Bourns"
			(at 238.76 209.55 0)
			(effects
				(font
					(size 1.27 1.27)
					(thickness 0.15)
				)
				(justify left bottom)
				(hide yes)
			)
		)
		(property "MPN" "CR0402-FX-4701GLF"
			(at 236.22 209.55 0)
			(effects
				(font
					(size 1.27 1.27)
					(thickness 0.15)
				)
				(justify left bottom)
				(hide yes)
			)
		)
		(property "Val" "4k7"
			(at 217.805 193.675 90)
			(effects
				(font
					(size 1.27 1.27)
					(thickness 0.15)
				)
				(justify right)
			)
		)
		(property "License" "Apache-2.0"
			(at 241.3 209.55 0)
			(effects
				(font
					(size 1.27 1.27)
					(thickness 0.15)
				)
				(justify left bottom)
				(hide yes)
			)
		)
		(property "Author" "Antmicro"
			(at 243.84 209.55 0)
			(effects
				(font
					(size 1.27 1.27)
					(thickness 0.15)
				)
				(justify left bottom)
				(hide yes)
			)
		)
		(property "Tolerance" "1%"
			(at 226.06 209.55 0)
			(effects
				(font
					(size 1.27 1.27)
				)
				(justify left bottom)
				(hide yes)
			)
		)
		(pin "1"
		)
		(pin "2"
		)
		(instances
			(project "data-center-rdimm-ddr5-tester"
				(path ""
					(reference "R5")
					(unit 1)
				)
			)
		)
	)
	(symbol
		(lib_id "antmicroResistors0402:R_22R_0402")
		(at 226.06 207.01 0)
		(unit 1)
		(exclude_from_sim no)
		(in_bom yes)
		(on_board yes)
		(dnp no)
		(property "Reference" "R9"
			(at 232.41 205.74 0)
			(effects
				(font
					(size 1.27 1.27)
				)
			)
		)
		(property "Value" "R_22R_0402"
			(at 246.38 219.71 0)
			(effects
				(font
					(size 1.27 1.27)
					(thickness 0.15)
				)
				(justify left bottom)
				(hide yes)
			)
		)
		(property "Footprint" "antmicro-footprints:R_0402_1005Metric"
			(at 246.38 222.25 0)
			(effects
				(font
					(size 1.27 1.27)
					(thickness 0.15)
				)
				(justify left bottom)
				(hide yes)
			)
		)
		(property "Datasheet" "https://www.bourns.com/docs/product-datasheets/cr.pdf"
			(at 246.38 224.79 0)
			(effects
				(font
					(size 1.27 1.27)
					(thickness 0.15)
				)
				(justify left bottom)
				(hide yes)
			)
		)
		(property "Description" ""
			(at 226.06 207.01 0)
			(effects
				(font
					(size 1.27 1.27)
				)
				(hide yes)
			)
		)
		(property "Manufacturer" "Bourns"
			(at 246.38 229.87 0)
			(effects
				(font
					(size 1.27 1.27)
					(thickness 0.15)
				)
				(justify left bottom)
				(hide yes)
			)
		)
		(property "MPN" "CR0402-FX-22R0GLF"
			(at 246.38 227.33 0)
			(effects
				(font
					(size 1.27 1.27)
					(thickness 0.15)
				)
				(justify left bottom)
				(hide yes)
			)
		)
		(property "Val" "22R"
			(at 224.155 205.74 0)
			(effects
				(font
					(size 1.27 1.27)
					(thickness 0.15)
				)
			)
		)
		(property "License" "Apache-2.0"
			(at 246.38 232.41 0)
			(effects
				(font
					(size 1.27 1.27)
					(thickness 0.15)
				)
				(justify left bottom)
				(hide yes)
			)
		)
		(property "Author" "Antmicro"
			(at 246.38 234.95 0)
			(effects
				(font
					(size 1.27 1.27)
					(thickness 0.15)
				)
				(justify left bottom)
				(hide yes)
			)
		)
		(property "Tolerance" "1%"
			(at 246.38 217.17 0)
			(effects
				(font
					(size 1.27 1.27)
				)
				(justify left bottom)
				(hide yes)
			)
		)
		(pin "1"
		)
		(pin "2"
		)
		(instances
			(project "data-center-rdimm-ddr5-tester"
				(path ""
					(reference "R9")
					(unit 1)
				)
			)
		)
	)
	(symbol
		(lib_id "antmicroCapacitors0402:C_100n_0402")
		(at 158.75 203.2 90)
		(mirror x)
		(unit 1)
		(exclude_from_sim no)
		(in_bom yes)
		(on_board yes)
		(dnp no)
		(fields_autoplaced yes)
		(property "Reference" "C5"
			(at 161.29 204.4763 90)
			(effects
				(font
					(size 1.27 1.27)
				)
				(justify right)
			)
		)
		(property "Value" "C_100n_0402"
			(at 168.91 223.52 0)
			(effects
				(font
					(size 1.27 1.27)
					(thickness 0.15)
				)
				(justify left bottom)
				(hide yes)
			)
		)
		(property "Footprint" "antmicro-footprints:C_0402_1005Metric"
			(at 171.45 223.52 0)
			(effects
				(font
					(size 1.27 1.27)
					(thickness 0.15)
				)
				(justify left bottom)
				(hide yes)
			)
		)
		(property "Datasheet" "https://www.murata.com/products/productdetail?partno=GRM155R61H104KE14%23"
			(at 173.99 223.52 0)
			(effects
				(font
					(size 1.27 1.27)
					(thickness 0.15)
				)
				(justify left bottom)
				(hide yes)
			)
		)
		(property "Description" ""
			(at 158.75 203.2 0)
			(effects
				(font
					(size 1.27 1.27)
				)
				(hide yes)
			)
		)
		(property "Manufacturer" "Murata"
			(at 179.07 223.52 0)
			(effects
				(font
					(size 1.27 1.27)
					(thickness 0.15)
				)
				(justify left bottom)
				(hide yes)
			)
		)
		(property "MPN" "GRM155R61H104KE14D"
			(at 176.53 223.52 0)
			(effects
				(font
					(size 1.27 1.27)
					(thickness 0.15)
				)
				(justify left bottom)
				(hide yes)
			)
		)
		(property "Val" "100n"
			(at 161.29 207.6512 90)
			(effects
				(font
					(size 1.27 1.27)
					(thickness 0.15)
				)
				(justify right)
			)
		)
		(property "License" "Apache-2.0"
			(at 181.61 223.52 0)
			(effects
				(font
					(size 1.27 1.27)
					(thickness 0.15)
				)
				(justify left bottom)
				(hide yes)
			)
		)
		(property "Author" "Antmicro"
			(at 184.15 223.52 0)
			(effects
				(font
					(size 1.27 1.27)
					(thickness 0.15)
				)
				(justify left bottom)
				(hide yes)
			)
		)
		(property "Voltage" "50V"
			(at 186.69 223.52 0)
			(effects
				(font
					(size 1.27 1.27)
				)
				(justify left bottom)
				(hide yes)
			)
		)
		(property "Dielectric" "X5R"
			(at 189.23 223.52 0)
			(effects
				(font
					(size 1.27 1.27)
				)
				(justify left bottom)
				(hide yes)
			)
		)
		(pin "1"
		)
		(pin "2"
		)
		(instances
			(project "data-center-rdimm-ddr5-tester"
				(path ""
					(reference "C5")
					(unit 1)
				)
			)
		)
	)
	(symbol
		(lib_id "antmicropower:GND")
		(at 236.22 223.52 0)
		(unit 1)
		(exclude_from_sim no)
		(in_bom yes)
		(on_board yes)
		(dnp no)
		(fields_autoplaced yes)
		(property "Reference" "#PWR0172"
			(at 236.22 229.87 0)
			(effects
				(font
					(size 1.27 1.27)
				)
				(hide yes)
			)
		)
		(property "Value" "GND"
			(at 234.315 227.965 0)
			(effects
				(font
					(size 1.27 1.27)
					(thickness 0.15)
				)
				(justify left bottom)
			)
		)
		(property "Footprint" ""
			(at 245.11 231.14 0)
			(effects
				(font
					(size 1.27 1.27)
					(thickness 0.15)
				)
				(justify left bottom)
				(hide yes)
			)
		)
		(property "Datasheet" ""
			(at 245.11 236.22 0)
			(effects
				(font
					(size 1.27 1.27)
					(thickness 0.15)
				)
				(justify left bottom)
				(hide yes)
			)
		)
		(property "Description" ""
			(at 236.22 223.52 0)
			(effects
				(font
					(size 1.27 1.27)
				)
				(hide yes)
			)
		)
		(property "Author" "Antmicro"
			(at 245.11 228.6 0)
			(effects
				(font
					(size 1.27 1.27)
					(thickness 0.15)
				)
				(justify left bottom)
				(hide yes)
			)
		)
		(property "License" "Apache-2.0"
			(at 245.11 231.14 0)
			(effects
				(font
					(size 1.27 1.27)
					(thickness 0.15)
				)
				(justify left bottom)
				(hide yes)
			)
		)
		(pin "1"
		)
		(instances
			(project "data-center-rdimm-ddr5-tester"
				(path ""
					(reference "#PWR0172")
					(unit 1)
				)
			)
		)
	)
	(symbol
		(lib_id "antmicroMemory:IS66WVH16M8DALL-166B1LI")
		(at 200.66 57.15 0)
		(unit 1)
		(exclude_from_sim no)
		(in_bom yes)
		(on_board yes)
		(dnp no)
		(fields_autoplaced yes)
		(property "Reference" "U1"
			(at 215.9 49.53 0)
			(effects
				(font
					(size 1.27 1.27)
					(thickness 0.15)
				)
			)
		)
		(property "Value" "IS66WVH16M8DALL-166B1LI"
			(at 246.38 67.31 0)
			(effects
				(font
					(size 1.27 1.27)
					(thickness 0.15)
				)
				(justify left bottom)
				(hide yes)
			)
		)
		(property "Footprint" "antmicro-footprints:FBGA-25-24_6x8mm_Layout5x5_P1mm"
			(at 246.38 69.85 0)
			(effects
				(font
					(size 1.27 1.27)
					(thickness 0.15)
				)
				(justify left bottom)
				(hide yes)
			)
		)
		(property "Datasheet" "https://www.issi.com/WW/pdf/66-67WVH16M8DALL-BLL.pdf"
			(at 246.38 72.39 0)
			(effects
				(font
					(size 1.27 1.27)
					(thickness 0.15)
				)
				(justify left bottom)
				(hide yes)
			)
		)
		(property "Description" ""
			(at 200.66 57.15 0)
			(effects
				(font
					(size 1.27 1.27)
				)
				(hide yes)
			)
		)
		(property "Manufacturer" "ISSI"
			(at 246.38 74.93 0)
			(effects
				(font
					(size 1.27 1.27)
					(thickness 0.15)
				)
				(justify left bottom)
				(hide yes)
			)
		)
		(property "MPN" "IS66WVH16M8DALL-166B1LI"
			(at 215.9 52.07 0)
			(effects
				(font
					(size 1.27 1.27)
					(thickness 0.15)
				)
			)
		)
		(property "Author" "Antmicro"
			(at 246.38 77.47 0)
			(effects
				(font
					(size 1.27 1.27)
					(thickness 0.15)
				)
				(justify left bottom)
				(hide yes)
			)
		)
		(property "License" "Apache-2.0"
			(at 246.38 80.01 0)
			(effects
				(font
					(size 1.27 1.27)
					(thickness 0.15)
				)
				(justify left bottom)
				(hide yes)
			)
		)
		(pin "D1"
		)
		(pin "C5"
		)
		(pin "B3"
		)
		(pin "D5"
		)
		(pin "E3"
		)
		(pin "A3"
		)
		(pin "D2"
		)
		(pin "A4"
		)
		(pin "D4"
		)
		(pin "B1"
		)
		(pin "D3"
		)
		(pin "E5"
		)
		(pin "E4"
		)
		(pin "B2"
		)
		(pin "A5"
		)
		(pin "A2"
		)
		(pin "B5"
		)
		(pin "C1"
		)
		(pin "E2"
		)
		(pin "C3"
		)
		(pin "C2"
		)
		(pin "E1"
		)
		(pin "B4"
		)
		(pin "C4"
		)
		(instances
			(project "data-center-rdimm-ddr5-tester"
				(path ""
					(reference "U1")
					(unit 1)
				)
			)
		)
	)
	(symbol
		(lib_id "antmicroMemory:W25Q128JWEIQ")
		(at 189.23 199.39 0)
		(mirror y)
		(unit 1)
		(exclude_from_sim no)
		(in_bom yes)
		(on_board yes)
		(dnp no)
		(property "Reference" "U27"
			(at 179.07 191.77 0)
			(effects
				(font
					(size 1.27 1.27)
					(thickness 0.15)
				)
			)
		)
		(property "Value" "W25Q128JWEIQ"
			(at 148.59 207.01 0)
			(effects
				(font
					(size 1.27 1.27)
					(thickness 0.15)
				)
				(justify left bottom)
				(hide yes)
			)
		)
		(property "Footprint" "antmicro-footprints:WSON-8_6x8x0.5mm_P1.27mm"
			(at 148.59 209.55 0)
			(effects
				(font
					(size 1.27 1.27)
					(thickness 0.15)
				)
				(justify left bottom)
				(hide yes)
			)
		)
		(property "Datasheet" "https://www.winbond.com/resource-files/W25Q128JW_RevG_07292021%20Plus.pdf"
			(at 148.59 212.09 0)
			(effects
				(font
					(size 1.27 1.27)
					(thickness 0.15)
				)
				(justify left bottom)
				(hide yes)
			)
		)
		(property "Description" ""
			(at 189.23 199.39 0)
			(effects
				(font
					(size 1.27 1.27)
				)
				(hide yes)
			)
		)
		(property "Manufacturer" "Winbond"
			(at 148.59 214.63 0)
			(effects
				(font
					(size 1.27 1.27)
					(thickness 0.15)
				)
				(justify left bottom)
				(hide yes)
			)
		)
		(property "MPN" "W25Q128JWEIQ TR"
			(at 179.07 194.31 0)
			(effects
				(font
					(size 1.27 1.27)
					(thickness 0.15)
				)
			)
		)
		(property "Author" "Antmicro"
			(at 148.59 217.17 0)
			(effects
				(font
					(size 1.27 1.27)
					(thickness 0.15)
				)
				(justify left bottom)
				(hide yes)
			)
		)
		(property "License" "Apache-2.0"
			(at 148.59 219.71 0)
			(effects
				(font
					(size 1.27 1.27)
					(thickness 0.15)
				)
				(justify left bottom)
				(hide yes)
			)
		)
		(pin "7"
		)
		(pin "3"
		)
		(pin "4"
		)
		(pin "1"
		)
		(pin "2"
		)
		(pin "6"
		)
		(pin "9"
		)
		(pin "5"
		)
		(pin "8"
		)
		(instances
			(project "data-center-rdimm-ddr5-tester"
				(path ""
					(reference "U27")
					(unit 1)
				)
			)
		)
	)
	(symbol
		(lib_id "antmicroResistors0402:R_2k2_0402")
		(at 199.39 189.23 270)
		(unit 1)
		(exclude_from_sim no)
		(in_bom yes)
		(on_board yes)
		(dnp no)
		(property "Reference" "R3"
			(at 199.39 188.5949 90)
			(effects
				(font
					(size 1.27 1.27)
				)
				(justify left)
			)
		)
		(property "Value" "R_2k2_0402"
			(at 186.69 209.55 0)
			(effects
				(font
					(size 1.27 1.27)
					(thickness 0.15)
				)
				(justify left bottom)
				(hide yes)
			)
		)
		(property "Footprint" "antmicro-footprints:R_0402_1005Metric"
			(at 184.15 209.55 0)
			(effects
				(font
					(size 1.27 1.27)
					(thickness 0.15)
				)
				(justify left bottom)
				(hide yes)
			)
		)
		(property "Datasheet" "https://www.bourns.com/docs/product-datasheets/cr.pdf"
			(at 181.61 209.55 0)
			(effects
				(font
					(size 1.27 1.27)
					(thickness 0.15)
				)
				(justify left bottom)
				(hide yes)
			)
		)
		(property "Description" ""
			(at 199.39 189.23 0)
			(effects
				(font
					(size 1.27 1.27)
				)
				(hide yes)
			)
		)
		(property "Manufacturer" "Bourns"
			(at 176.53 209.55 0)
			(effects
				(font
					(size 1.27 1.27)
					(thickness 0.15)
				)
				(justify left bottom)
				(hide yes)
			)
		)
		(property "MPN" "CR0402-FX-2201GLF"
			(at 179.07 209.55 0)
			(effects
				(font
					(size 1.27 1.27)
					(thickness 0.15)
				)
				(justify left bottom)
				(hide yes)
			)
		)
		(property "Val" "2k2"
			(at 201.295 193.6749 90)
			(effects
				(font
					(size 1.27 1.27)
					(thickness 0.15)
				)
				(justify left)
			)
		)
		(property "License" "Apache-2.0"
			(at 173.99 209.55 0)
			(effects
				(font
					(size 1.27 1.27)
					(thickness 0.15)
				)
				(justify left bottom)
				(hide yes)
			)
		)
		(property "Author" "Antmicro"
			(at 171.45 209.55 0)
			(effects
				(font
					(size 1.27 1.27)
					(thickness 0.15)
				)
				(justify left bottom)
				(hide yes)
			)
		)
		(property "Tolerance" "1%"
			(at 189.23 209.55 0)
			(effects
				(font
					(size 1.27 1.27)
				)
				(justify left bottom)
				(hide yes)
			)
		)
		(pin "1"
		)
		(pin "2"
		)
		(instances
			(project "data-center-rdimm-ddr5-tester"
				(path ""
					(reference "R3")
					(unit 1)
				)
			)
		)
	)
	(symbol
		(lib_id "antmicropower:+1V8")
		(at 191.77 45.72 0)
		(unit 1)
		(exclude_from_sim no)
		(in_bom yes)
		(on_board yes)
		(dnp no)
		(fields_autoplaced yes)
		(property "Reference" "#PWR01"
			(at 207.01 48.26 0)
			(effects
				(font
					(size 1.27 1.27)
					(thickness 0.15)
				)
				(justify left bottom)
				(hide yes)
			)
		)
		(property "Value" "+1V8"
			(at 191.77 41.275 0)
			(effects
				(font
					(size 1.27 1.27)
					(thickness 0.15)
				)
			)
		)
		(property "Footprint" ""
			(at 207.01 53.34 0)
			(effects
				(font
					(size 1.27 1.27)
					(thickness 0.15)
				)
				(justify left bottom)
				(hide yes)
			)
		)
		(property "Datasheet" ""
			(at 207.01 55.88 0)
			(effects
				(font
					(size 1.27 1.27)
					(thickness 0.15)
				)
				(justify left bottom)
				(hide yes)
			)
		)
		(property "Description" ""
			(at 191.77 45.72 0)
			(effects
				(font
					(size 1.27 1.27)
				)
				(hide yes)
			)
		)
		(property "Author" "Antmicro"
			(at 207.01 50.8 0)
			(effects
				(font
					(size 1.27 1.27)
					(thickness 0.15)
				)
				(justify left bottom)
				(hide yes)
			)
		)
		(property "License" "Apache-2.0"
			(at 207.01 53.34 0)
			(effects
				(font
					(size 1.27 1.27)
					(thickness 0.15)
				)
				(justify left bottom)
				(hide yes)
			)
		)
		(pin "1"
		)
		(instances
			(project "data-center-rdimm-ddr5-tester"
				(path ""
					(reference "#PWR01")
					(unit 1)
				)
			)
		)
	)
	(symbol
		(lib_id "antmicroResistors0402:R_4k7_0402")
		(at 208.28 189.23 90)
		(mirror x)
		(unit 1)
		(exclude_from_sim no)
		(in_bom yes)
		(on_board yes)
		(dnp no)
		(property "Reference" "R4"
			(at 208.28 188.5949 90)
			(effects
				(font
					(size 1.27 1.27)
				)
				(justify right)
			)
		)
		(property "Value" "R_4k7_0402"
			(at 220.98 209.55 0)
			(effects
				(font
					(size 1.27 1.27)
					(thickness 0.15)
				)
				(justify left bottom)
				(hide yes)
			)
		)
		(property "Footprint" "antmicro-footprints:R_0402_1005Metric"
			(at 223.52 209.55 0)
			(effects
				(font
					(size 1.27 1.27)
					(thickness 0.15)
				)
				(justify left bottom)
				(hide yes)
			)
		)
		(property "Datasheet" "https://www.bourns.com/docs/product-datasheets/cr.pdf"
			(at 226.06 209.55 0)
			(effects
				(font
					(size 1.27 1.27)
					(thickness 0.15)
				)
				(justify left bottom)
				(hide yes)
			)
		)
		(property "Description" ""
			(at 208.28 189.23 0)
			(effects
				(font
					(size 1.27 1.27)
				)
				(hide yes)
			)
		)
		(property "Manufacturer" "Bourns"
			(at 231.14 209.55 0)
			(effects
				(font
					(size 1.27 1.27)
					(thickness 0.15)
				)
				(justify left bottom)
				(hide yes)
			)
		)
		(property "MPN" "CR0402-FX-4701GLF"
			(at 228.6 209.55 0)
			(effects
				(font
					(size 1.27 1.27)
					(thickness 0.15)
				)
				(justify left bottom)
				(hide yes)
			)
		)
		(property "Val" "4k7"
			(at 210.185 193.6749 90)
			(effects
				(font
					(size 1.27 1.27)
					(thickness 0.15)
				)
				(justify right)
			)
		)
		(property "License" "Apache-2.0"
			(at 233.68 209.55 0)
			(effects
				(font
					(size 1.27 1.27)
					(thickness 0.15)
				)
				(justify left bottom)
				(hide yes)
			)
		)
		(property "Author" "Antmicro"
			(at 236.22 209.55 0)
			(effects
				(font
					(size 1.27 1.27)
					(thickness 0.15)
				)
				(justify left bottom)
				(hide yes)
			)
		)
		(property "Tolerance" "1%"
			(at 218.44 209.55 0)
			(effects
				(font
					(size 1.27 1.27)
				)
				(justify left bottom)
				(hide yes)
			)
		)
		(pin "1"
		)
		(pin "2"
		)
		(instances
			(project "data-center-rdimm-ddr5-tester"
				(path ""
					(reference "R4")
					(unit 1)
				)
			)
		)
	)
	(symbol
		(lib_id "antmicroResistors0402:R_22R_0402")
		(at 226.06 199.39 0)
		(unit 1)
		(exclude_from_sim no)
		(in_bom yes)
		(on_board yes)
		(dnp no)
		(property "Reference" "R6"
			(at 232.41 198.12 0)
			(effects
				(font
					(size 1.27 1.27)
				)
			)
		)
		(property "Value" "R_22R_0402"
			(at 246.38 212.09 0)
			(effects
				(font
					(size 1.27 1.27)
					(thickness 0.15)
				)
				(justify left bottom)
				(hide yes)
			)
		)
		(property "Footprint" "antmicro-footprints:R_0402_1005Metric"
			(at 246.38 214.63 0)
			(effects
				(font
					(size 1.27 1.27)
					(thickness 0.15)
				)
				(justify left bottom)
				(hide yes)
			)
		)
		(property "Datasheet" "https://www.bourns.com/docs/product-datasheets/cr.pdf"
			(at 246.38 217.17 0)
			(effects
				(font
					(size 1.27 1.27)
					(thickness 0.15)
				)
				(justify left bottom)
				(hide yes)
			)
		)
		(property "Description" ""
			(at 226.06 199.39 0)
			(effects
				(font
					(size 1.27 1.27)
				)
				(hide yes)
			)
		)
		(property "Manufacturer" "Bourns"
			(at 246.38 222.25 0)
			(effects
				(font
					(size 1.27 1.27)
					(thickness 0.15)
				)
				(justify left bottom)
				(hide yes)
			)
		)
		(property "MPN" "CR0402-FX-22R0GLF"
			(at 246.38 219.71 0)
			(effects
				(font
					(size 1.27 1.27)
					(thickness 0.15)
				)
				(justify left bottom)
				(hide yes)
			)
		)
		(property "Val" "22R"
			(at 224.155 198.12 0)
			(effects
				(font
					(size 1.27 1.27)
					(thickness 0.15)
				)
			)
		)
		(property "License" "Apache-2.0"
			(at 246.38 224.79 0)
			(effects
				(font
					(size 1.27 1.27)
					(thickness 0.15)
				)
				(justify left bottom)
				(hide yes)
			)
		)
		(property "Author" "Antmicro"
			(at 246.38 227.33 0)
			(effects
				(font
					(size 1.27 1.27)
					(thickness 0.15)
				)
				(justify left bottom)
				(hide yes)
			)
		)
		(property "Tolerance" "1%"
			(at 246.38 209.55 0)
			(effects
				(font
					(size 1.27 1.27)
				)
				(justify left bottom)
				(hide yes)
			)
		)
		(pin "1"
		)
		(pin "2"
		)
		(instances
			(project "data-center-rdimm-ddr5-tester"
				(path ""
					(reference "R6")
					(unit 1)
				)
			)
		)
	)
	(symbol
		(lib_id "antmicropower:GND")
		(at 167.64 213.36 0)
		(unit 1)
		(exclude_from_sim no)
		(in_bom yes)
		(on_board yes)
		(dnp no)
		(fields_autoplaced yes)
		(property "Reference" "#PWR0169"
			(at 167.64 219.71 0)
			(effects
				(font
					(size 1.27 1.27)
				)
				(hide yes)
			)
		)
		(property "Value" "GND"
			(at 165.735 217.805 0)
			(effects
				(font
					(size 1.27 1.27)
					(thickness 0.15)
				)
				(justify left bottom)
			)
		)
		(property "Footprint" ""
			(at 176.53 220.98 0)
			(effects
				(font
					(size 1.27 1.27)
					(thickness 0.15)
				)
				(justify left bottom)
				(hide yes)
			)
		)
		(property "Datasheet" ""
			(at 176.53 226.06 0)
			(effects
				(font
					(size 1.27 1.27)
					(thickness 0.15)
				)
				(justify left bottom)
				(hide yes)
			)
		)
		(property "Description" ""
			(at 167.64 213.36 0)
			(effects
				(font
					(size 1.27 1.27)
				)
				(hide yes)
			)
		)
		(property "Author" "Antmicro"
			(at 176.53 218.44 0)
			(effects
				(font
					(size 1.27 1.27)
					(thickness 0.15)
				)
				(justify left bottom)
				(hide yes)
			)
		)
		(property "License" "Apache-2.0"
			(at 176.53 220.98 0)
			(effects
				(font
					(size 1.27 1.27)
					(thickness 0.15)
				)
				(justify left bottom)
				(hide yes)
			)
		)
		(pin "1"
		)
		(instances
			(project "data-center-rdimm-ddr5-tester"
				(path ""
					(reference "#PWR0169")
					(unit 1)
				)
			)
		)
	)
	(symbol
		(lib_id "antmicropower:+1V8")
		(at 199.39 184.15 0)
		(unit 1)
		(exclude_from_sim no)
		(in_bom yes)
		(on_board yes)
		(dnp no)
		(fields_autoplaced yes)
		(property "Reference" "#PWR024"
			(at 214.63 186.69 0)
			(effects
				(font
					(size 1.27 1.27)
					(thickness 0.15)
				)
				(justify left bottom)
				(hide yes)
			)
		)
		(property "Value" "+1V8"
			(at 199.39 179.705 0)
			(effects
				(font
					(size 1.27 1.27)
					(thickness 0.15)
				)
			)
		)
		(property "Footprint" ""
			(at 214.63 191.77 0)
			(effects
				(font
					(size 1.27 1.27)
					(thickness 0.15)
				)
				(justify left bottom)
				(hide yes)
			)
		)
		(property "Datasheet" ""
			(at 214.63 194.31 0)
			(effects
				(font
					(size 1.27 1.27)
					(thickness 0.15)
				)
				(justify left bottom)
				(hide yes)
			)
		)
		(property "Description" ""
			(at 199.39 184.15 0)
			(effects
				(font
					(size 1.27 1.27)
				)
				(hide yes)
			)
		)
		(property "Author" "Antmicro"
			(at 214.63 189.23 0)
			(effects
				(font
					(size 1.27 1.27)
					(thickness 0.15)
				)
				(justify left bottom)
				(hide yes)
			)
		)
		(property "License" "Apache-2.0"
			(at 214.63 191.77 0)
			(effects
				(font
					(size 1.27 1.27)
					(thickness 0.15)
				)
				(justify left bottom)
				(hide yes)
			)
		)
		(pin "1"
		)
		(instances
			(project "data-center-rdimm-ddr5-tester"
				(path ""
					(reference "#PWR024")
					(unit 1)
				)
			)
		)
	)
	(symbol
		(lib_id "antmicropower:GND")
		(at 158.75 213.36 0)
		(unit 1)
		(exclude_from_sim no)
		(in_bom yes)
		(on_board yes)
		(dnp no)
		(fields_autoplaced yes)
		(property "Reference" "#PWR0171"
			(at 158.75 219.71 0)
			(effects
				(font
					(size 1.27 1.27)
				)
				(hide yes)
			)
		)
		(property "Value" "GND"
			(at 156.845 217.805 0)
			(effects
				(font
					(size 1.27 1.27)
					(thickness 0.15)
				)
				(justify left bottom)
			)
		)
		(property "Footprint" ""
			(at 167.64 220.98 0)
			(effects
				(font
					(size 1.27 1.27)
					(thickness 0.15)
				)
				(justify left bottom)
				(hide yes)
			)
		)
		(property "Datasheet" ""
			(at 167.64 226.06 0)
			(effects
				(font
					(size 1.27 1.27)
					(thickness 0.15)
				)
				(justify left bottom)
				(hide yes)
			)
		)
		(property "Description" ""
			(at 158.75 213.36 0)
			(effects
				(font
					(size 1.27 1.27)
				)
				(hide yes)
			)
		)
		(property "Author" "Antmicro"
			(at 167.64 218.44 0)
			(effects
				(font
					(size 1.27 1.27)
					(thickness 0.15)
				)
				(justify left bottom)
				(hide yes)
			)
		)
		(property "License" "Apache-2.0"
			(at 167.64 220.98 0)
			(effects
				(font
					(size 1.27 1.27)
					(thickness 0.15)
				)
				(justify left bottom)
				(hide yes)
			)
		)
		(pin "1"
		)
		(instances
			(project "data-center-rdimm-ddr5-tester"
				(path ""
					(reference "#PWR0171")
					(unit 1)
				)
			)
		)
	)
	(symbol
		(lib_id "antmicroResistors0402:R_100R_0402")
		(at 236.22 215.9 270)
		(unit 1)
		(exclude_from_sim no)
		(in_bom no)
		(on_board yes)
		(dnp yes)
		(property "Reference" "R10"
			(at 238.76 217.17 90)
			(effects
				(font
					(size 1.27 1.27)
				)
				(justify left)
			)
		)
		(property "Value" "R_100R_0402"
			(at 223.52 236.22 0)
			(effects
				(font
					(size 1.27 1.27)
					(thickness 0.15)
				)
				(justify left bottom)
				(hide yes)
			)
		)
		(property "Footprint" "antmicro-footprints:R_0402_1005Metric"
			(at 220.98 236.22 0)
			(effects
				(font
					(size 1.27 1.27)
					(thickness 0.15)
				)
				(justify left bottom)
				(hide yes)
			)
		)
		(property "Datasheet" "https://www.bourns.com/docs/product-datasheets/cr.pdf"
			(at 218.44 236.22 0)
			(effects
				(font
					(size 1.27 1.27)
					(thickness 0.15)
				)
				(justify left bottom)
				(hide yes)
			)
		)
		(property "Description" ""
			(at 236.22 215.9 0)
			(effects
				(font
					(size 1.27 1.27)
				)
				(hide yes)
			)
		)
		(property "Manufacturer" "Bourns"
			(at 213.36 236.22 0)
			(effects
				(font
					(size 1.27 1.27)
					(thickness 0.15)
				)
				(justify left bottom)
				(hide yes)
			)
		)
		(property "MPN" "CR0402-FX-1000GLF"
			(at 215.9 236.22 0)
			(effects
				(font
					(size 1.27 1.27)
					(thickness 0.15)
				)
				(justify left bottom)
				(hide yes)
			)
		)
		(property "Val" "100R"
			(at 238.76 220.3449 90)
			(effects
				(font
					(size 1.27 1.27)
					(thickness 0.15)
				)
				(justify left)
			)
		)
		(property "License" "Apache-2.0"
			(at 210.82 236.22 0)
			(effects
				(font
					(size 1.27 1.27)
					(thickness 0.15)
				)
				(justify left bottom)
				(hide yes)
			)
		)
		(property "Author" "Antmicro"
			(at 208.28 236.22 0)
			(effects
				(font
					(size 1.27 1.27)
					(thickness 0.15)
				)
				(justify left bottom)
				(hide yes)
			)
		)
		(property "Tolerance" "1%"
			(at 226.06 236.22 0)
			(effects
				(font
					(size 1.27 1.27)
				)
				(justify left bottom)
				(hide yes)
			)
		)
		(pin "1"
		)
		(pin "2"
		)
		(instances
			(project "data-center-rdimm-ddr5-tester"
				(path ""
					(reference "R10")
					(unit 1)
				)
			)
		)
	)
	(symbol
		(lib_id "antmicropower:+1V8")
		(at 264.16 55.88 0)
		(unit 1)
		(exclude_from_sim no)
		(in_bom yes)
		(on_board yes)
		(dnp no)
		(fields_autoplaced yes)
		(property "Reference" "#PWR02"
			(at 279.4 58.42 0)
			(effects
				(font
					(size 1.27 1.27)
					(thickness 0.15)
				)
				(justify left bottom)
				(hide yes)
			)
		)
		(property "Value" "+1V8"
			(at 264.16 51.435 0)
			(effects
				(font
					(size 1.27 1.27)
					(thickness 0.15)
				)
			)
		)
		(property "Footprint" ""
			(at 279.4 63.5 0)
			(effects
				(font
					(size 1.27 1.27)
					(thickness 0.15)
				)
				(justify left bottom)
				(hide yes)
			)
		)
		(property "Datasheet" ""
			(at 279.4 66.04 0)
			(effects
				(font
					(size 1.27 1.27)
					(thickness 0.15)
				)
				(justify left bottom)
				(hide yes)
			)
		)
		(property "Description" ""
			(at 264.16 55.88 0)
			(effects
				(font
					(size 1.27 1.27)
				)
				(hide yes)
			)
		)
		(property "Author" "Antmicro"
			(at 279.4 60.96 0)
			(effects
				(font
					(size 1.27 1.27)
					(thickness 0.15)
				)
				(justify left bottom)
				(hide yes)
			)
		)
		(property "License" "Apache-2.0"
			(at 279.4 63.5 0)
			(effects
				(font
					(size 1.27 1.27)
					(thickness 0.15)
				)
				(justify left bottom)
				(hide yes)
			)
		)
		(pin "1"
		)
		(instances
			(project "data-center-rdimm-ddr5-tester"
				(path ""
					(reference "#PWR02")
					(unit 1)
				)
			)
		)
	)
)
